# BASEBOARD_FAB2 (Tioga Pass) — schematic netlist excerpt (pin names and nets, part order shuffled) for the footprints in the layout excerpt that follows; sources: Cadence DE-HDL packaged netlist, KiCad conversion of Wiwynn_Tioga_Pass_MB.brd

C2D19  CAP_A  22.0UF 4V 20% X6S  pkg 0603V  page 76 : A = PVCCIN_CPU1 ; B = GND
R8F5  RES  1.00K 1% CHIP  pkg 0402  page 240 : A = P3V3_STBY ; B = PWRGD_P3V3_STBY_R
R9E17  RES  22.1 1.0% CHIP  pkg 0402  page 139 : A = RMII_SPRNGVLLE_BMC_PCH_RXD0_R ; B = RMII_SPRNGVLLE_BMC_PCH_RXD0

(kicad_pcb
	(version 20260206)
	(generator "pcbnew")
	(generator_version "10.0")
	(general
		(thickness 1.6)
		(legacy_teardrops no)
	)
	(paper "A4")
	(title_block
		(title "Wiwynn_Tioga_Pass_MB.brd")
		(comment 1 "Tioga Pass / footprints 904-906 of 4770")
	)
	(layers
		(0 "F.Cu" signal "TOP")
		(4 "In1.Cu" signal "L2GND")
		(6 "In2.Cu" signal "L3")
		(8 "In3.Cu" signal "L4GND")
		(10 "In4.Cu" signal "L5")
		(12 "In5.Cu" signal "L6GND")
		(14 "In6.Cu" signal "L7VCC")
		(16 "In7.Cu" signal "L8VCC")
		(18 "In8.Cu" signal "L9GND")
		(20 "In9.Cu" signal "L10")
		(22 "In10.Cu" signal "L11GND")
		(24 "In11.Cu" signal "L12")
		(26 "In12.Cu" signal "L13GND")
		(2 "B.Cu" signal "BOTTOM")
		(9 "F.Adhes" user "F.Adhesive")
		(11 "B.Adhes" user "B.Adhesive")
		(13 "F.Paste" user "Package Geometry/Pastemask Top")
		(15 "B.Paste" user "Package Geometry/Pastemask Bottom")
		(5 "F.SilkS" user "Ref Des/Silkscreen Top")
		(7 "B.SilkS" user "Ref Des/Silkscreen Bottom")
		(1 "F.Mask" user "Board Geometry/Soldermask Top")
		(3 "B.Mask" user "Board Geometry/Soldermask Bottom")
		(17 "Dwgs.User" user "User.Drawings")
		(19 "Cmts.User" user "User.Comments")
		(21 "Eco1.User" user "User.Eco1")
		(23 "Eco2.User" user "User.Eco2")
		(25 "Edge.Cuts" user "Board Geometry/Outline")
		(27 "Margin" user)
		(31 "F.CrtYd" user "Package Geometry/Place Bound Top")
		(29 "B.CrtYd" user "Package Geometry/Place Bound Bottom")
		(35 "F.Fab" user "Ref Des/Assembly Top")
		(33 "B.Fab" user "Ref Des/Assembly Bottom")
	)
	(footprint ""
		(layer "F.Cu")
		(at 93.20784 -77.636116)
		(property "Reference" "C2D19"
			(at 0 0 0)
			(layer "F.SilkS")
			(hide yes)
			(effects
				(font
					(size 1.27 1.27)
				)
			)
		)
		(property "Value" ""
			(at 0 0 0)
			(layer "F.Fab")
			(effects
				(font
					(size 1.27 1.27)
				)
			)
		)
		(duplicate_pad_numbers_are_jumpers no)
		(fp_poly
			(pts
				(xy -0.4953 -0.2032) (xy 0.4953 -0.2032) (xy 0.4953 1.6002) (xy -0.4953 1.6002)
			)
			(stroke
				(width 0)
				(type default)
			)
			(fill no)
			(layer "F.CrtYd")
		)
		(fp_line
			(start -0.4953 -0.2032)
			(end 0.4953 -0.2032)
			(stroke
				(width 0.1)
				(type default)
			)
			(layer "F.Fab")
		)
		(fp_line
			(start -0.4953 1.6002)
			(end -0.4953 -0.2032)
			(stroke
				(width 0.1)
				(type default)
			)
			(layer "F.Fab")
		)
		(fp_line
			(start 0.4953 -0.2032)
			(end 0.4953 1.6002)
			(stroke
				(width 0.1)
				(type default)
			)
			(layer "F.Fab")
		)
		(fp_line
			(start 0.4953 1.6002)
			(end -0.4953 1.6002)
			(stroke
				(width 0.1)
				(type default)
			)
			(layer "F.Fab")
		)
		(pad "1" smd rect
			(at 0 0)
			(size 0.762 0.889)
			(layers "F.Cu" "F.Mask" "F.Paste")
			(net "PVCCIN_CPU1")
		)
		(pad "2" smd rect
			(at 0 1.397)
			(size 0.762 0.889)
			(layers "F.Cu" "F.Mask" "F.Paste")
			(net "GND")
		)
		(zone
			(layer "F.Cu")
			(hatch none 0.5)
			(connect_pads
				(clearance 0)
			)
			(min_thickness 0.25)
			(keepout
				(tracks not_allowed)
				(vias allowed)
				(pads allowed)
				(copperpour not_allowed)
				(footprints allowed)
			)
			(placement
				(enabled no)
				(sheetname "")
			)
			(fill
				(thermal_gap 0.5)
				(thermal_bridge_width 0.5)
				(island_removal_mode 0)
			)
			(polygon
				(pts
					(xy 92.82684 -77.191616) (xy 93.58884 -77.191616) (xy 93.58884 -76.683616) (xy 92.82684 -76.683616)
				)
			)
		)
	)
	(footprint ""
		(layer "F.Cu")
		(at 491.0455 -43.0784 90)
		(property "Reference" "R9E17"
			(at 0 0 90)
			(layer "F.SilkS")
			(hide yes)
			(effects
				(font
					(size 1.27 1.27)
				)
			)
		)
		(property "Value" ""
			(at 0 0 90)
			(layer "F.Fab")
			(effects
				(font
					(size 1.27 1.27)
				)
			)
		)
		(duplicate_pad_numbers_are_jumpers no)
		(fp_poly
			(pts
				(xy -0.2794 -0.1016) (xy 0.2794 -0.1016) (xy 0.2794 0.9906) (xy -0.2794 0.9906)
			)
			(stroke
				(width 0)
				(type default)
			)
			(fill no)
			(layer "F.CrtYd")
		)
		(fp_line
			(start 0.2794 -0.1016)
			(end -0.2794 -0.1016)
			(stroke
				(width 0.1)
				(type default)
			)
			(layer "F.Fab")
		)
		(fp_line
			(start -0.2794 -0.1016)
			(end -0.2794 0.9906)
			(stroke
				(width 0.1)
				(type default)
			)
			(layer "F.Fab")
		)
		(fp_line
			(start 0.2794 0.9906)
			(end 0.2794 -0.1016)
			(stroke
				(width 0.1)
				(type default)
			)
			(layer "F.Fab")
		)
		(fp_line
			(start -0.2794 0.9906)
			(end 0.2794 0.9906)
			(stroke
				(width 0.1)
				(type default)
			)
			(layer "F.Fab")
		)
		(pad "1" smd rect
			(at 0 0 90)
			(size 0.508 0.508)
			(layers "F.Cu" "F.Mask" "F.Paste")
			(net "RMII_SPRNGVLLE_BMC_PCH_RXD0_R")
		)
		(pad "2" smd rect
			(at 0 0.889 90)
			(size 0.508 0.508)
			(layers "F.Cu" "F.Mask" "F.Paste")
			(net "RMII_SPRNGVLLE_BMC_PCH_RXD0")
		)
		(zone
			(layer "F.Cu")
			(hatch none 0.5)
			(connect_pads
				(clearance 0)
			)
			(min_thickness 0.25)
			(keepout
				(tracks allowed)
				(vias not_allowed)
				(pads allowed)
				(copperpour not_allowed)
				(footprints allowed)
			)
			(placement
				(enabled no)
				(sheetname "")
			)
			(fill
				(thermal_gap 0.5)
				(thermal_bridge_width 0.5)
				(island_removal_mode 0)
			)
			(polygon
				(pts
					(xy 491.2995 -42.8244) (xy 491.2995 -43.3324) (xy 491.6805 -43.3324) (xy 491.6805 -42.8244)
				)
			)
		)
		(zone
			(layer "F.Cu")
			(hatch none 0.5)
			(connect_pads
				(clearance 0)
			)
			(min_thickness 0.25)
			(keepout
				(tracks not_allowed)
				(vias allowed)
				(pads allowed)
				(copperpour not_allowed)
				(footprints allowed)
			)
			(placement
				(enabled no)
				(sheetname "")
			)
			(fill
				(thermal_gap 0.5)
				(thermal_bridge_width 0.5)
				(island_removal_mode 0)
			)
			(polygon
				(pts
					(xy 491.6805 -42.8244) (xy 491.6805 -43.3324) (xy 491.2995 -43.3324) (xy 491.2995 -42.8244)
				)
			)
		)
	)
	(footprint ""
		(layer "F.Cu")
		(at 465.582 -20.4343 180)
		(property "Reference" "R8F5"
			(at 0 0 180)
			(layer "F.SilkS")
			(hide yes)
			(effects
				(font
					(size 1.27 1.27)
				)
			)
		)
		(property "Value" ""
			(at 0 0 180)
			(layer "F.Fab")
			(effects
				(font
					(size 1.27 1.27)
				)
			)
		)
		(duplicate_pad_numbers_are_jumpers no)
		(fp_rect
			(start -0.2794 -0.1016)
			(end 0.2794 0.9906)
			(stroke
				(width 0)
				(type default)
			)
			(fill no)
			(layer "F.CrtYd")
		)
		(fp_line
			(start 0.2794 0.9906)
			(end 0.2794 -0.1016)
			(stroke
				(width 0.1)
				(type default)
			)
			(layer "F.Fab")
		)
		(fp_line
			(start 0.2794 -0.1016)
			(end -0.2794 -0.1016)
			(stroke
				(width 0.1)
				(type default)
			)
			(layer "F.Fab")
		)
		(fp_line
			(start -0.2794 0.9906)
			(end 0.2794 0.9906)
			(stroke
				(width 0.1)
				(type default)
			)
			(layer "F.Fab")
		)
		(fp_line
			(start -0.2794 -0.1016)
			(end -0.2794 0.9906)
			(stroke
				(width 0.1)
				(type default)
			)
			(layer "F.Fab")
		)
		(pad "1" smd rect
			(at 0 0 180)
			(size 0.508 0.508)
			(layers "F.Cu" "F.Mask" "F.Paste")
			(net "P3V3_STBY")
		)
		(pad "2" smd rect
			(at 0 0.889 180)
			(size 0.508 0.508)
			(layers "F.Cu" "F.Mask" "F.Paste")
			(net "PWRGD_P3V3_STBY_R")
		)
		(zone
			(layer "F.Cu")
			(hatch none 0.5)
			(connect_pads
				(clearance 0)
			)
			(min_thickness 0.25)
			(keepout
				(tracks not_allowed)
				(vias allowed)
				(pads allowed)
				(copperpour not_allowed)
				(footprints allowed)
			)
			(placement
				(enabled no)
				(sheetname "")
			)
			(fill
				(thermal_gap 0.5)
				(thermal_bridge_width 0.5)
				(island_removal_mode 0)
			)
			(polygon
				(pts
					(xy 465.836 -20.6883) (xy 465.836 -21.0693) (xy 465.328 -21.0693) (xy 465.328 -20.6883)
				)
			)
		)
		(zone
			(layer "F.Cu")
			(hatch none 0.5)
			(connect_pads
				(clearance 0)
			)
			(min_thickness 0.25)
			(keepout
				(tracks allowed)
				(vias not_allowed)
				(pads allowed)
				(copperpour not_allowed)
				(footprints allowed)
			)
			(placement
				(enabled no)
				(sheetname "")
			)
			(fill
				(thermal_gap 0.5)
				(thermal_bridge_width 0.5)
				(island_removal_mode 0)
			)
			(polygon
				(pts
					(xy 465.836 -20.6883) (xy 465.836 -21.0693) (xy 465.328 -21.0693) (xy 465.328 -20.6883)
				)
			)
		)
	)
)
